(kicad_pcb
	(version 20260206)
	(generator "pcbnew")
	(generator_version "10.0")
	(general
		(thickness 1.6)
		(legacy_teardrops no)
	)
	(paper "A4")
	(title_block
		(title "fcb — Lightning_FCB_BRD.brd")
		(comment 1 "Lightning (Wiwynn / Facebook NVMe JBOF) / footprints 482-488 of 495")
	)
	(layers
		(0 "F.Cu" signal "TOP")
		(4 "In1.Cu" signal "L2GND")
		(6 "In2.Cu" signal "L3VCC")
		(2 "B.Cu" signal "BOTTOM")
		(9 "F.Adhes" user "F.Adhesive")
		(11 "B.Adhes" user "B.Adhesive")
		(13 "F.Paste" user "Package Geometry/Pastemask Top")
		(15 "B.Paste" user "Package Geometry/Pastemask Bottom")
		(5 "F.SilkS" user "Ref Des/Silkscreen Top")
		(7 "B.SilkS" user "Ref Des/Silkscreen Bottom")
		(1 "F.Mask" user "Board Geometry/Soldermask Top")
		(3 "B.Mask" user "Board Geometry/Soldermask Bottom")
		(17 "Dwgs.User" user "User.Drawings")
		(19 "Cmts.User" user "User.Comments")
		(21 "Eco1.User" user "User.Eco1")
		(23 "Eco2.User" user "User.Eco2")
		(25 "Edge.Cuts" user "Board Geometry/Outline")
		(27 "Margin" user)
		(31 "F.CrtYd" user "Package Geometry/Place Bound Top")
		(29 "B.CrtYd" user "Package Geometry/Place Bound Bottom")
		(35 "F.Fab" user "Ref Des/Assembly Top")
		(33 "B.Fab" user "Ref Des/Assembly Bottom")
	)
	(footprint ""
		(layer "F.Cu")
		(at 20.3454 -245.4148 -90)
		(property "Reference" "PC41"
			(at 0 0 270)
			(layer "F.SilkS")
			(hide yes)
			(effects
				(font
					(size 1.27 1.27)
				)
			)
		)
		(property "Value" "SCD1U16V2KX-3GP"
			(at 1.1811 -2.7051 270)
			(unlocked yes)
			(layer "F.Fab")
			(hide yes)
			(effects
				(font
					(size 1.016 1.016)
					(thickness 0.1524)
				)
			)
		)
		(property "Device Type" "C402H22"
			(at 1.1811 -4.2291 270)
			(unlocked yes)
			(layer "F.Fab")
			(hide yes)
			(effects
				(font
					(size 1.016 1.016)
					(thickness 0.1524)
				)
			)
		)
		(duplicate_pad_numbers_are_jumpers no)
		(fp_rect
			(start -0.4318 0.9525)
			(end 0.4318 -0.9525)
			(stroke
				(width 0)
				(type default)
			)
			(fill no)
			(layer "F.CrtYd")
		)
		(fp_rect
			(start -0.4318 0.9525)
			(end 0.4318 -0.9525)
			(stroke
				(width 0)
				(type default)
			)
			(fill no)
			(layer "F.Fab")
		)
		(pad "1" smd custom
			(at 0 -0.4445 270)
			(size 0.1524 0.1524)
			(layers "F.Cu" "F.Mask" "F.Paste")
			(net "P3V3_BS_NET")
			(options
				(clearance outline)
				(anchor circle)
			)
			(primitives
				(gr_poly
					(pts
						(arc
							(start 0.3048 -0.2032)
							(mid 0.275042 -0.275042)
							(end 0.2032 -0.3048)
						)
						(arc
							(start -0.2032 -0.3048)
							(mid -0.275042 -0.275042)
							(end -0.3048 -0.2032)
						)
						(arc
							(start -0.3048 0.2032)
							(mid -0.275042 0.275042)
							(end -0.2032 0.3048)
						)
						(arc
							(start 0.2032 0.3048)
							(mid 0.275042 0.275042)
							(end 0.3048 0.2032)
						)
					)
					(width 0)
					(fill yes)
				)
			)
		)
		(pad "2" smd custom
			(at 0 0.4445 270)
			(size 0.1524 0.1524)
			(layers "F.Cu" "F.Mask" "F.Paste")
			(net "P3V3_LX")
			(options
				(clearance outline)
				(anchor circle)
			)
			(primitives
				(gr_poly
					(pts
						(arc
							(start 0.3048 -0.2032)
							(mid 0.275042 -0.275042)
							(end 0.2032 -0.3048)
						)
						(arc
							(start -0.2032 -0.3048)
							(mid -0.275042 -0.275042)
							(end -0.3048 -0.2032)
						)
						(arc
							(start -0.3048 0.2032)
							(mid -0.275042 0.275042)
							(end -0.2032 0.3048)
						)
						(arc
							(start 0.2032 0.3048)
							(mid 0.275042 0.275042)
							(end 0.3048 0.2032)
						)
					)
					(width 0)
					(fill yes)
				)
			)
		)
	)
	(footprint ""
		(layer "F.Cu")
		(at 17.526 -16.129 -90)
		(property "Reference" "R65"
			(at 0 0 270)
			(layer "F.SilkS")
			(hide yes)
			(effects
				(font
					(size 1.27 1.27)
				)
			)
		)
		(property "Value" "4K7R2F-GP"
			(at 0.064008 -3.993896 270)
			(unlocked yes)
			(layer "F.Fab")
			(hide yes)
			(effects
				(font
					(size 1.016 1.016)
					(thickness 0.1524)
				)
			)
		)
		(property "Device Type" "R402H16"
			(at 0.064008 -5.517896 270)
			(unlocked yes)
			(layer "F.Fab")
			(hide yes)
			(effects
				(font
					(size 1.016 1.016)
					(thickness 0.1524)
				)
			)
		)
		(duplicate_pad_numbers_are_jumpers no)
		(fp_line
			(start -0.508 -0.9398)
			(end -0.508 0.9398)
			(stroke
				(width 0.1524)
				(type default)
			)
			(layer "F.SilkS")
		)
		(fp_line
			(start 0.508 -0.9398)
			(end -0.508 -0.9398)
			(stroke
				(width 0.1524)
				(type default)
			)
			(layer "F.SilkS")
		)
		(fp_rect
			(start -0.508 0.9398)
			(end 0.508 -0.9398)
			(stroke
				(width 0)
				(type default)
			)
			(fill no)
			(layer "F.CrtYd")
		)
		(fp_rect
			(start -0.508 0.9398)
			(end 0.508 -0.9398)
			(stroke
				(width 0)
				(type default)
			)
			(fill no)
			(layer "F.Fab")
		)
		(pad "1" smd custom
			(at 0 -0.4445 270)
			(size 0.1397 0.1397)
			(layers "F.Cu" "F.Mask" "F.Paste")
			(net "P12V")
			(options
				(clearance outline)
				(anchor circle)
			)
			(primitives
				(gr_poly
					(pts
						(arc
							(start -0.1778 -0.2794)
							(mid -0.249642 -0.249642)
							(end -0.2794 -0.1778)
						)
						(arc
							(start -0.2794 0.1778)
							(mid -0.249642 0.249642)
							(end -0.1778 0.2794)
						)
						(arc
							(start 0.1778 0.2794)
							(mid 0.249642 0.249642)
							(end 0.2794 0.1778)
						)
						(arc
							(start 0.2794 -0.1778)
							(mid 0.249642 -0.249642)
							(end 0.1778 -0.2794)
						)
					)
					(width 0)
					(fill yes)
				)
			)
		)
		(pad "2" smd custom
			(at 0 0.4445 270)
			(size 0.1397 0.1397)
			(layers "F.Cu" "F.Mask" "F.Paste")
			(net "PWM_OUT_FAN6_NET")
			(options
				(clearance outline)
				(anchor circle)
			)
			(primitives
				(gr_poly
					(pts
						(arc
							(start -0.1778 -0.2794)
							(mid -0.249642 -0.249642)
							(end -0.2794 -0.1778)
						)
						(arc
							(start -0.2794 0.1778)
							(mid -0.249642 0.249642)
							(end -0.1778 0.2794)
						)
						(arc
							(start 0.1778 0.2794)
							(mid 0.249642 0.249642)
							(end 0.2794 0.1778)
						)
						(arc
							(start 0.2794 -0.1778)
							(mid 0.249642 -0.249642)
							(end 0.1778 -0.2794)
						)
					)
					(width 0)
					(fill yes)
				)
			)
		)
	)
	(footprint ""
		(layer "F.Cu")
		(at 21.336 -375.285 -90)
		(property "Reference" "PC10"
			(at 0 0 270)
			(layer "F.SilkS")
			(hide yes)
			(effects
				(font
					(size 1.27 1.27)
				)
			)
		)
		(property "Value" "SC1U25V5KX-1GP"
			(at -0.0762 -6.1214 270)
			(unlocked yes)
			(layer "F.Fab")
			(hide yes)
			(effects
				(font
					(size 1.016 1.016)
					(thickness 0.1524)
				)
			)
		)
		(property "Device Type" "C805H58"
			(at -0.0762 -8.1534 270)
			(unlocked yes)
			(layer "F.Fab")
			(hide yes)
			(effects
				(font
					(size 1.016 1.016)
					(thickness 0.1524)
				)
			)
		)
		(duplicate_pad_numbers_are_jumpers no)
		(fp_line
			(start 0.635 0)
			(end -0.635 0)
			(stroke
				(width 0.508)
				(type default)
			)
			(layer "F.SilkS")
		)
		(fp_rect
			(start -0.9652 1.778)
			(end 0.9652 -1.778)
			(stroke
				(width 0)
				(type default)
			)
			(fill no)
			(layer "F.CrtYd")
		)
		(fp_poly
			(pts
				(xy -0.9652 -1.778) (xy 0.9652 -1.778) (xy 0.9652 1.778) (xy -0.9652 1.778)
			)
			(stroke
				(width 0)
				(type default)
			)
			(fill no)
			(layer "F.Fab")
		)
		(pad "1" smd rect
			(at 0 -0.9652 270)
			(size 1.397 1.143)
			(layers "F.Cu" "F.Mask" "F.Paste")
			(net "ADM1276_UV")
		)
		(pad "2" smd rect
			(at 0 0.9652 270)
			(size 1.397 1.143)
			(layers "F.Cu" "F.Mask" "F.Paste")
			(net "GND")
		)
	)
	(footprint ""
		(layer "F.Cu")
		(at 14.8844 -47.5742 -90)
		(property "Reference" "R185"
			(at 0 0 270)
			(layer "F.SilkS")
			(hide yes)
			(effects
				(font
					(size 1.27 1.27)
				)
			)
		)
		(property "Value" "0R2J-2-GP"
			(at 0.064008 -3.993896 270)
			(unlocked yes)
			(layer "F.Fab")
			(hide yes)
			(effects
				(font
					(size 1.016 1.016)
					(thickness 0.1524)
				)
			)
		)
		(property "Device Type" "R402H16"
			(at 0.064008 -5.517896 270)
			(unlocked yes)
			(layer "F.Fab")
			(hide yes)
			(effects
				(font
					(size 1.016 1.016)
					(thickness 0.1524)
				)
			)
		)
		(duplicate_pad_numbers_are_jumpers no)
		(fp_line
			(start -0.508 -0.9398)
			(end -0.508 0.9398)
			(stroke
				(width 0.1524)
				(type default)
			)
			(layer "F.SilkS")
		)
		(fp_line
			(start 0.508 -0.9398)
			(end -0.508 -0.9398)
			(stroke
				(width 0.1524)
				(type default)
			)
			(layer "F.SilkS")
		)
		(fp_rect
			(start -0.508 0.9398)
			(end 0.508 -0.9398)
			(stroke
				(width 0)
				(type default)
			)
			(fill no)
			(layer "F.CrtYd")
		)
		(fp_rect
			(start -0.508 0.9398)
			(end 0.508 -0.9398)
			(stroke
				(width 0)
				(type default)
			)
			(fill no)
			(layer "F.Fab")
		)
		(pad "1" smd custom
			(at 0 -0.4445 270)
			(size 0.1397 0.1397)
			(layers "F.Cu" "F.Mask" "F.Paste")
			(net "SD_LATCH_RELEASE_L")
			(options
				(clearance outline)
				(anchor circle)
			)
			(primitives
				(gr_poly
					(pts
						(arc
							(start -0.1778 -0.2794)
							(mid -0.249642 -0.249642)
							(end -0.2794 -0.1778)
						)
						(arc
							(start -0.2794 0.1778)
							(mid -0.249642 0.249642)
							(end -0.1778 0.2794)
						)
						(arc
							(start 0.1778 0.2794)
							(mid 0.249642 0.249642)
							(end 0.2794 0.1778)
						)
						(arc
							(start 0.2794 -0.1778)
							(mid 0.249642 -0.249642)
							(end 0.1778 -0.2794)
						)
					)
					(width 0)
					(fill yes)
				)
			)
		)
		(pad "2" smd custom
			(at 0 0.4445 270)
			(size 0.1397 0.1397)
			(layers "F.Cu" "F.Mask" "F.Paste")
			(net "D_LATCH_PRE#")
			(options
				(clearance outline)
				(anchor circle)
			)
			(primitives
				(gr_poly
					(pts
						(arc
							(start -0.1778 -0.2794)
							(mid -0.249642 -0.249642)
							(end -0.2794 -0.1778)
						)
						(arc
							(start -0.2794 0.1778)
							(mid -0.249642 0.249642)
							(end -0.1778 0.2794)
						)
						(arc
							(start 0.1778 0.2794)
							(mid 0.249642 0.249642)
							(end 0.2794 0.1778)
						)
						(arc
							(start 0.2794 -0.1778)
							(mid 0.249642 -0.249642)
							(end 0.1778 -0.2794)
						)
					)
					(width 0)
					(fill yes)
				)
			)
		)
	)
	(footprint ""
		(layer "F.Cu")
		(at 34.544 -240.3094 180)
		(property "Reference" "R55"
			(at 0 0 180)
			(layer "F.SilkS")
			(hide yes)
			(effects
				(font
					(size 1.27 1.27)
				)
			)
		)
		(property "Value" "4K7R2J-2-GP"
			(at 0.064008 -3.993896 180)
			(unlocked yes)
			(layer "F.Fab")
			(hide yes)
			(effects
				(font
					(size 1.016 1.016)
					(thickness 0.1524)
				)
			)
		)
		(property "Device Type" "R402H16"
			(at 0.064008 -5.517896 180)
			(unlocked yes)
			(layer "F.Fab")
			(hide yes)
			(effects
				(font
					(size 1.016 1.016)
					(thickness 0.1524)
				)
			)
		)
		(duplicate_pad_numbers_are_jumpers no)
		(fp_line
			(start 0.508 -0.9398)
			(end -0.508 -0.9398)
			(stroke
				(width 0.1524)
				(type default)
			)
			(layer "F.SilkS")
		)
		(fp_line
			(start -0.508 -0.9398)
			(end -0.508 0.9398)
			(stroke
				(width 0.1524)
				(type default)
			)
			(layer "F.SilkS")
		)
		(fp_rect
			(start -0.508 0.9398)
			(end 0.508 -0.9398)
			(stroke
				(width 0)
				(type default)
			)
			(fill no)
			(layer "F.CrtYd")
		)
		(fp_rect
			(start -0.508 0.9398)
			(end 0.508 -0.9398)
			(stroke
				(width 0)
				(type default)
			)
			(fill no)
			(layer "F.Fab")
		)
		(pad "1" smd custom
			(at 0 -0.4445 180)
			(size 0.1397 0.1397)
			(layers "F.Cu" "F.Mask" "F.Paste")
			(net "GND")
			(options
				(clearance outline)
				(anchor circle)
			)
			(primitives
				(gr_poly
					(pts
						(arc
							(start -0.1778 -0.2794)
							(mid -0.249642 -0.249642)
							(end -0.2794 -0.1778)
						)
						(arc
							(start -0.2794 0.1778)
							(mid -0.249642 0.249642)
							(end -0.1778 0.2794)
						)
						(arc
							(start 0.1778 0.2794)
							(mid 0.249642 0.249642)
							(end 0.2794 0.1778)
						)
						(arc
							(start 0.2794 -0.1778)
							(mid 0.249642 -0.249642)
							(end 0.1778 -0.2794)
						)
					)
					(width 0)
					(fill yes)
				)
			)
		)
		(pad "2" smd custom
			(at 0 0.4445 180)
			(size 0.1397 0.1397)
			(layers "F.Cu" "F.Mask" "F.Paste")
			(net "LED_DRV_A1")
			(options
				(clearance outline)
				(anchor circle)
			)
			(primitives
				(gr_poly
					(pts
						(arc
							(start -0.1778 -0.2794)
							(mid -0.249642 -0.249642)
							(end -0.2794 -0.1778)
						)
						(arc
							(start -0.2794 0.1778)
							(mid -0.249642 0.249642)
							(end -0.1778 0.2794)
						)
						(arc
							(start 0.1778 0.2794)
							(mid 0.249642 0.249642)
							(end 0.2794 0.1778)
						)
						(arc
							(start 0.2794 -0.1778)
							(mid 0.249642 -0.249642)
							(end 0.1778 -0.2794)
						)
					)
					(width 0)
					(fill yes)
				)
			)
		)
	)
	(footprint ""
		(layer "F.Cu")
		(at 18.7706 -141.5034 180)
		(property "Reference" "PR106"
			(at 0 0 180)
			(layer "F.SilkS")
			(hide yes)
			(effects
				(font
					(size 1.27 1.27)
				)
			)
		)
		(property "Value" "1KR2F-3-GP"
			(at 0.064008 -3.993896 180)
			(unlocked yes)
			(layer "F.Fab")
			(hide yes)
			(effects
				(font
					(size 1.016 1.016)
					(thickness 0.1524)
				)
			)
		)
		(property "Device Type" "R402H16"
			(at 0.064008 -5.517896 180)
			(unlocked yes)
			(layer "F.Fab")
			(hide yes)
			(effects
				(font
					(size 1.016 1.016)
					(thickness 0.1524)
				)
			)
		)
		(duplicate_pad_numbers_are_jumpers no)
		(fp_line
			(start 0.508 -0.9398)
			(end -0.508 -0.9398)
			(stroke
				(width 0.1524)
				(type default)
			)
			(layer "F.SilkS")
		)
		(fp_line
			(start -0.508 -0.9398)
			(end -0.508 0.9398)
			(stroke
				(width 0.1524)
				(type default)
			)
			(layer "F.SilkS")
		)
		(fp_rect
			(start -0.508 0.9398)
			(end 0.508 -0.9398)
			(stroke
				(width 0)
				(type default)
			)
			(fill no)
			(layer "F.CrtYd")
		)
		(fp_rect
			(start -0.508 0.9398)
			(end 0.508 -0.9398)
			(stroke
				(width 0)
				(type default)
			)
			(fill no)
			(layer "F.Fab")
		)
		(pad "1" smd custom
			(at 0 -0.4445 180)
			(size 0.1397 0.1397)
			(layers "F.Cu" "F.Mask" "F.Paste")
			(net "P12VU_2490_PG")
			(options
				(clearance outline)
				(anchor circle)
			)
			(primitives
				(gr_poly
					(pts
						(arc
							(start -0.1778 -0.2794)
							(mid -0.249642 -0.249642)
							(end -0.2794 -0.1778)
						)
						(arc
							(start -0.2794 0.1778)
							(mid -0.249642 0.249642)
							(end -0.1778 0.2794)
						)
						(arc
							(start 0.1778 0.2794)
							(mid 0.249642 0.249642)
							(end 0.2794 0.1778)
						)
						(arc
							(start 0.2794 -0.1778)
							(mid 0.249642 -0.249642)
							(end 0.1778 -0.2794)
						)
					)
					(width 0)
					(fill yes)
				)
			)
		)
		(pad "2" smd custom
			(at 0 0.4445 180)
			(size 0.1397 0.1397)
			(layers "F.Cu" "F.Mask" "F.Paste")
			(net "GND")
			(options
				(clearance outline)
				(anchor circle)
			)
			(primitives
				(gr_poly
					(pts
						(arc
							(start -0.1778 -0.2794)
							(mid -0.249642 -0.249642)
							(end -0.2794 -0.1778)
						)
						(arc
							(start -0.2794 0.1778)
							(mid -0.249642 0.249642)
							(end -0.1778 0.2794)
						)
						(arc
							(start 0.1778 0.2794)
							(mid 0.249642 0.249642)
							(end 0.2794 0.1778)
						)
						(arc
							(start 0.2794 -0.1778)
							(mid 0.249642 -0.249642)
							(end 0.1778 -0.2794)
						)
					)
					(width 0)
					(fill yes)
				)
			)
		)
	)
	(footprint ""
		(layer "F.Cu")
		(at 4.040124 -127.340106 -90)
		(property "Reference" "CN5"
			(at 0 0 270)
			(layer "F.SilkS")
			(hide yes)
			(effects
				(font
					(size 1.27 1.27)
				)
			)
		)
		(property "Value" "JWT-CON5-42-GP"
			(at -7.8105 2.9591 270)
			(unlocked yes)
			(layer "F.Fab")
			(hide yes)
			(effects
				(font
					(size 1.016 1.016)
					(thickness 0.1524)
				)
			)
		)
		(property "Device Type" "A2541WR0-1TX5PA-6T-0E"
			(at -7.8105 1.4351 270)
			(unlocked yes)
			(layer "F.Fab")
			(hide yes)
			(effects
				(font
					(size 1.016 1.016)
					(thickness 0.1524)
				)
			)
		)
		(duplicate_pad_numbers_are_jumpers no)
		(fp_line
			(start -6.604 10.287)
			(end 6.604 10.287)
			(stroke
				(width 0.1524)
				(type default)
			)
			(layer "F.SilkS")
		)
		(fp_line
			(start 6.604 10.287)
			(end 6.604 -0.9652)
			(stroke
				(width 0.1524)
				(type default)
			)
			(layer "F.SilkS")
		)
		(fp_line
			(start -6.604 -0.9652)
			(end -6.604 10.287)
			(stroke
				(width 0.1524)
				(type default)
			)
			(layer "F.SilkS")
		)
		(fp_line
			(start 6.604 -0.9652)
			(end -6.604 -0.9652)
			(stroke
				(width 0.1524)
				(type default)
			)
			(layer "F.SilkS")
		)
		(fp_line
			(start -6.731 -1.0922)
			(end -6.731 0.1778)
			(stroke
				(width 0.4064)
				(type default)
			)
			(layer "F.SilkS")
		)
		(fp_line
			(start -5.461 -1.0922)
			(end -6.731 -1.0922)
			(stroke
				(width 0.4064)
				(type default)
			)
			(layer "F.SilkS")
		)
		(fp_circle
			(center -5.08 0)
			(end -5.08 -1.0668)
			(stroke
				(width 0.3048)
				(type default)
			)
			(fill no)
			(layer "F.SilkS")
		)
		(fp_circle
			(center -2.54 0)
			(end -2.54 -1.0668)
			(stroke
				(width 0.3048)
				(type default)
			)
			(fill no)
			(layer "F.SilkS")
		)
		(fp_circle
			(center 0 0)
			(end 0 -1.0668)
			(stroke
				(width 0.3048)
				(type default)
			)
			(fill no)
			(layer "F.SilkS")
		)
		(fp_circle
			(center 2.54 0)
			(end 2.54 -1.0668)
			(stroke
				(width 0.3048)
				(type default)
			)
			(fill no)
			(layer "F.SilkS")
		)
		(fp_circle
			(center 5.08 0)
			(end 5.08 -1.0668)
			(stroke
				(width 0.3048)
				(type default)
			)
			(fill no)
			(layer "F.SilkS")
		)
		(fp_rect
			(start -6.35 10.033)
			(end 6.35 -0.3302)
			(stroke
				(width 0)
				(type default)
			)
			(fill no)
			(layer "F.CrtYd")
		)
		(fp_poly
			(pts
				(xy -6.35 -0.3302) (xy 6.858 -0.3302) (xy 6.858 -1.2192) (xy -6.858 -1.2192) (xy -6.858 10.541)
				(xy 6.858 10.541) (xy 6.858 -0.3175) (xy 6.35 -0.3175) (xy 6.35 10.033) (xy -6.35 10.033)
			)
			(stroke
				(width 0)
				(type default)
			)
			(fill no)
			(layer "F.CrtYd")
		)
		(fp_rect
			(start -6.858 10.541)
			(end 6.858 -1.2192)
			(stroke
				(width 0)
				(type default)
			)
			(fill no)
			(layer "F.Fab")
		)
		(pad "1" thru_hole circle
			(at -5.08 0 270)
			(size 1.4224 1.4224)
			(drill 1.016)
			(layers "*.Cu" "*.Mask")
			(remove_unused_layers no)
			(net "GND")
			(clearance 0.1524)
			(thermal_gap 0.1524)
		)
		(pad "2" thru_hole circle
			(at -2.54 0 270)
			(size 1.4224 1.4224)
			(drill 1.016)
			(layers "*.Cu" "*.Mask")
			(remove_unused_layers no)
			(net "P12V_FAN5")
			(clearance 0.1524)
			(thermal_gap 0.1524)
		)
		(pad "3" thru_hole circle
			(at 0 0 270)
			(size 1.4224 1.4224)
			(drill 1.016)
			(layers "*.Cu" "*.Mask")
			(remove_unused_layers no)
			(net "FAN_TACH10")
			(clearance 0.1524)
			(thermal_gap 0.1524)
		)
		(pad "4" thru_hole circle
			(at 2.54 0 270)
			(size 1.4224 1.4224)
			(drill 1.016)
			(layers "*.Cu" "*.Mask")
			(remove_unused_layers no)
			(net "PWM_OUT_FAN5_NET")
			(clearance 0.1524)
			(thermal_gap 0.1524)
		)
		(pad "5" thru_hole circle
			(at 5.08 0 270)
			(size 1.4224 1.4224)
			(drill 1.016)
			(layers "*.Cu" "*.Mask")
			(remove_unused_layers no)
			(net "FAN_TACH9")
			(clearance 0.1524)
			(thermal_gap 0.1524)
		)
	)
)
